# S9S_MB_2U (Grand Teton) — schematic netlist excerpt (pin names and nets, part order shuffled) for the footprints in the layout excerpt that follows; sources: Cadence DE-HDL packaged netlist, KiCad conversion of 03242023_DA0F0TMBIJ0_F0T_Motherboard_J_brd_V01_OCP.brd

R1129  Q_RES  1K 1% CHIP  pkg 0402LF  page 158 : A = P3V3_AUX ; B = HP_LVC3_OCP_V3_1_PRSNT2
R3395  Q_RES  2.2K 5% CHIP  pkg 0402LF  page 231 : A = P3V3_AUX ; B = SMB_INA230_3V3AUX_SCL

(kicad_pcb
	(version 20260206)
	(generator "pcbnew")
	(generator_version "10.0")
	(general
		(thickness 1.6)
		(legacy_teardrops no)
	)
	(paper "A4")
	(title_block
		(title "03242023_DA0F0TMBIJ0_F0T_Motherboard_J_brd_V01_OCP.brd")
		(comment 1 "Grand Teton / footprints 1502-1503 of 6105")
	)
	(layers
		(0 "F.Cu" signal "TOP")
		(4 "In1.Cu" signal "GND")
		(6 "In2.Cu" signal "IN1")
		(8 "In3.Cu" signal "GND1")
		(10 "In4.Cu" signal "IN2")
		(12 "In5.Cu" signal "GND2")
		(14 "In6.Cu" signal "IN3")
		(16 "In7.Cu" signal "GND3")
		(18 "In8.Cu" signal "VCC")
		(20 "In9.Cu" signal "VCC1")
		(22 "In10.Cu" signal "GND4")
		(24 "In11.Cu" signal "IN4")
		(26 "In12.Cu" signal "GND5")
		(28 "In13.Cu" signal "IN5")
		(30 "In14.Cu" signal "GND6")
		(32 "In15.Cu" signal "IN6")
		(34 "In16.Cu" signal "GND7")
		(2 "B.Cu" signal "BOTTOM")
		(9 "F.Adhes" user "F.Adhesive")
		(11 "B.Adhes" user "B.Adhesive")
		(13 "F.Paste" user "Package Geometry/Pastemask Top")
		(15 "B.Paste" user "Package Geometry/Pastemask Bottom")
		(5 "F.SilkS" user "Ref Des/Silkscreen Top")
		(7 "B.SilkS" user "Ref Des/Silkscreen Bottom")
		(1 "F.Mask" user "Board Geometry/Soldermask Top")
		(3 "B.Mask" user "Board Geometry/Soldermask Bottom")
		(17 "Dwgs.User" user "User.Drawings")
		(19 "Cmts.User" user "User.Comments")
		(21 "Eco1.User" user "User.Eco1")
		(23 "Eco2.User" user "User.Eco2")
		(25 "Edge.Cuts" user "Board Geometry/Outline")
		(27 "Margin" user)
		(31 "F.CrtYd" user "Package Geometry/Place Bound Top")
		(29 "B.CrtYd" user "Package Geometry/Place Bound Bottom")
		(35 "F.Fab" user "Ref Des/Assembly Top")
		(33 "B.Fab" user "Ref Des/Assembly Bottom")
	)
	(footprint ""
		(layer "F.Cu")
		(at 131.466844 -134.104126 180)
		(property "Reference" "R3395"
			(at 0 0 180)
			(layer "F.SilkS")
			(hide yes)
			(effects
				(font
					(size 1.27 1.27)
				)
			)
		)
		(property "Value" ""
			(at 0 0 180)
			(layer "F.Fab")
			(effects
				(font
					(size 1.27 1.27)
				)
			)
		)
		(duplicate_pad_numbers_are_jumpers no)
		(fp_line
			(start 0.7874 0.4064)
			(end -0.7874 0.4064)
			(stroke
				(width 0.1524)
				(type default)
			)
			(layer "F.SilkS")
		)
		(fp_line
			(start 0.7874 -0.4064)
			(end 0.7874 0.4064)
			(stroke
				(width 0.1524)
				(type default)
			)
			(layer "F.SilkS")
		)
		(fp_line
			(start -0.7874 0.4064)
			(end -0.7874 -0.4064)
			(stroke
				(width 0.1524)
				(type default)
			)
			(layer "F.SilkS")
		)
		(fp_line
			(start -0.7874 -0.4064)
			(end 0.7874 -0.4064)
			(stroke
				(width 0.1524)
				(type default)
			)
			(layer "F.SilkS")
		)
		(fp_line
			(start 0.67945 0.3048)
			(end 0.120396 0.3048)
			(stroke
				(width 0.1)
				(type default)
			)
			(layer "F.Fab")
		)
		(fp_line
			(start 0.67945 -0.3048)
			(end 0.67945 0.3048)
			(stroke
				(width 0.1)
				(type default)
			)
			(layer "F.Fab")
		)
		(fp_line
			(start 0.12065 -0.2794)
			(end 0.12065 -0.3048)
			(stroke
				(width 0.1)
				(type default)
			)
			(layer "F.Fab")
		)
		(fp_line
			(start 0.12065 -0.3048)
			(end 0.67945 -0.3048)
			(stroke
				(width 0.1)
				(type default)
			)
			(layer "F.Fab")
		)
		(fp_line
			(start 0.120396 0.3048)
			(end 0.120396 0.2794)
			(stroke
				(width 0.1)
				(type default)
			)
			(layer "F.Fab")
		)
		(fp_line
			(start 0.120396 0.2794)
			(end -0.12065 0.2794)
			(stroke
				(width 0.1)
				(type default)
			)
			(layer "F.Fab")
		)
		(fp_line
			(start -0.12065 0.3048)
			(end -0.67945 0.3048)
			(stroke
				(width 0.1)
				(type default)
			)
			(layer "F.Fab")
		)
		(fp_line
			(start -0.12065 0.2794)
			(end -0.12065 0.3048)
			(stroke
				(width 0.1)
				(type default)
			)
			(layer "F.Fab")
		)
		(fp_line
			(start -0.12065 -0.2794)
			(end 0.12065 -0.2794)
			(stroke
				(width 0.1)
				(type default)
			)
			(layer "F.Fab")
		)
		(fp_line
			(start -0.12065 -0.305054)
			(end -0.12065 -0.2794)
			(stroke
				(width 0.1)
				(type default)
			)
			(layer "F.Fab")
		)
		(fp_line
			(start -0.67945 0.3048)
			(end -0.67945 -0.305054)
			(stroke
				(width 0.1)
				(type default)
			)
			(layer "F.Fab")
		)
		(fp_line
			(start -0.67945 -0.305054)
			(end -0.12065 -0.305054)
			(stroke
				(width 0.1)
				(type default)
			)
			(layer "F.Fab")
		)
		(pad "1" smd circle
			(at -0.40005 0 180)
			(size 0 0)
			(layers "F.Cu" "F.Mask" "F.Paste")
			(net "P3V3_AUX")
		)
		(pad "2" smd circle
			(at 0.40005 0 180)
			(size 0 0)
			(layers "F.Cu" "F.Mask" "F.Paste")
			(net "SMB_INA230_3V3AUX_SCL")
		)
	)
	(footprint ""
		(layer "F.Cu")
		(at 446.694814 -110.038134)
		(property "Reference" "R1129"
			(at 0 0 0)
			(layer "F.SilkS")
			(hide yes)
			(effects
				(font
					(size 1.27 1.27)
				)
			)
		)
		(property "Value" ""
			(at 0 0 0)
			(layer "F.Fab")
			(effects
				(font
					(size 1.27 1.27)
				)
			)
		)
		(duplicate_pad_numbers_are_jumpers no)
		(fp_line
			(start -0.7874 -0.4064)
			(end 0.7874 -0.4064)
			(stroke
				(width 0.1524)
				(type default)
			)
			(layer "F.SilkS")
		)
		(fp_line
			(start -0.7874 0.4064)
			(end -0.7874 -0.4064)
			(stroke
				(width 0.1524)
				(type default)
			)
			(layer "F.SilkS")
		)
		(fp_line
			(start 0.7874 -0.4064)
			(end 0.7874 0.4064)
			(stroke
				(width 0.1524)
				(type default)
			)
			(layer "F.SilkS")
		)
		(fp_line
			(start 0.7874 0.4064)
			(end -0.7874 0.4064)
			(stroke
				(width 0.1524)
				(type default)
			)
			(layer "F.SilkS")
		)
		(fp_line
			(start -0.67945 -0.305054)
			(end -0.12065 -0.305054)
			(stroke
				(width 0.1)
				(type default)
			)
			(layer "F.Fab")
		)
		(fp_line
			(start -0.67945 0.3048)
			(end -0.67945 -0.305054)
			(stroke
				(width 0.1)
				(type default)
			)
			(layer "F.Fab")
		)
		(fp_line
			(start -0.12065 -0.305054)
			(end -0.12065 -0.2794)
			(stroke
				(width 0.1)
				(type default)
			)
			(layer "F.Fab")
		)
		(fp_line
			(start -0.12065 -0.2794)
			(end 0.12065 -0.2794)
			(stroke
				(width 0.1)
				(type default)
			)
			(layer "F.Fab")
		)
		(fp_line
			(start -0.12065 0.2794)
			(end -0.12065 0.3048)
			(stroke
				(width 0.1)
				(type default)
			)
			(layer "F.Fab")
		)
		(fp_line
			(start -0.12065 0.3048)
			(end -0.67945 0.3048)
			(stroke
				(width 0.1)
				(type default)
			)
			(layer "F.Fab")
		)
		(fp_line
			(start 0.120396 0.2794)
			(end -0.12065 0.2794)
			(stroke
				(width 0.1)
				(type default)
			)
			(layer "F.Fab")
		)
		(fp_line
			(start 0.120396 0.3048)
			(end 0.120396 0.2794)
			(stroke
				(width 0.1)
				(type default)
			)
			(layer "F.Fab")
		)
		(fp_line
			(start 0.12065 -0.3048)
			(end 0.67945 -0.3048)
			(stroke
				(width 0.1)
				(type default)
			)
			(layer "F.Fab")
		)
		(fp_line
			(start 0.12065 -0.2794)
			(end 0.12065 -0.3048)
			(stroke
				(width 0.1)
				(type default)
			)
			(layer "F.Fab")
		)
		(fp_line
			(start 0.67945 -0.3048)
			(end 0.67945 0.3048)
			(stroke
				(width 0.1)
				(type default)
			)
			(layer "F.Fab")
		)
		(fp_line
			(start 0.67945 0.3048)
			(end 0.120396 0.3048)
			(stroke
				(width 0.1)
				(type default)
			)
			(layer "F.Fab")
		)
		(pad "1" smd circle
			(at -0.40005 0)
			(size 0 0)
			(layers "F.Cu" "F.Mask" "F.Paste")
			(net "P3V3_AUX")
		)
		(pad "2" smd circle
			(at 0.40005 0)
			(size 0 0)
			(layers "F.Cu" "F.Mask" "F.Paste")
			(net "HP_LVC3_OCP_V3_1_PRSNT2")
		)
	)
)
